#ISCELL
  mstr_misc dns *
  *
#ISCELL
  mstr_symbols cad_note *
  *
#ISCELL
  mstr_symbols intel_corp_bpage *
  *
#ISCELL
  mstr_standard offpage *
  page147_i10
#CELL
  w_hdl ast2520a1-gp-gp *
  page147_i106
#ISCELL
  mstr_standard offpage *
  page147_i11
#ISCELL
  mstr_standard offpage *
  page147_i111
#ISCELL
  mstr_standard offpage *
  page147_i115
#ISCELL
  mstr_standard offpage *
  page147_i116
#ISCELL
  mstr_standard offpage *
  page147_i12
#ISCELL
  mstr_standard offpage *
  page147_i126
#ISCELL
  mstr_standard offpage *
  page147_i127
#ISCELL
  mstr_standard offpage *
  page147_i128
#CELL
  mstr_discrete res *
  page147_i129
#ISCELL
  mstr_standard offpage *
  page147_i13
#ISCELL
  mstr_standard offpage *
  page147_i131
#ISCELL
  mstr_standard offpage *
  page147_i132
#ISCELL
  mstr_standard offpage *
  page147_i134
#ISCELL
  mstr_standard offpage *
  page147_i135
#ISCELL
  mstr_standard offpage *
  page147_i137
#ISCELL
  mstr_standard offpage *
  page147_i138
#ISCELL
  mstr_standard offpage *
  page147_i139
#ISCELL
  mstr_standard offpage *
  page147_i14
#ISCELL
  mstr_standard offpage *
  page147_i140
#ISCELL
  mstr_standard offpage *
  page147_i143
#ISCELL
  mstr_standard offpage *
  page147_i144
#ISCELL
  mstr_symbols gnd *
  page147_i145
#ISCELL
  mstr_standard offpage *
  page147_i146
#ISCELL
  mstr_standard offpage *
  page147_i147
#ISCELL
  mstr_standard offpage *
  page147_i148
#ISCELL
  mstr_standard offpage *
  page147_i149
#ISCELL
  mstr_standard offpage *
  page147_i15
#ISCELL
  mstr_standard offpage *
  page147_i150
#CELL
  mstr_discrete res *
  page147_i151
#ISCELL
  mstr_standard offpage *
  page147_i152
#ISCELL
  mstr_standard offpage *
  page147_i153
#ISCELL
  mstr_standard offpage *
  page147_i154
#ISCELL
  mstr_standard offpage *
  page147_i155
#CELL
  mstr_discrete res *
  page147_i156
#ISCELL
  mstr_symbols gnd *
  page147_i157
#ISCELL
  mstr_standard offpage *
  page147_i158
#CELL
  mstr_discrete res *
  page147_i159
#ISCELL
  mstr_standard offpage *
  page147_i16
#CELL
  dev_discrete cap_a *
  page147_i160
#CELL
  dev_discrete cap_a *
  page147_i161
#CELL
  dev_discrete cap_a *
  page147_i162
#ISCELL
  mstr_standard offpage *
  page147_i163
#CELL
  mstr_discrete res *
  page147_i164
#ISCELL
  mstr_symbols gnd *
  page147_i165
#ISCELL
  mstr_standard offpage *
  page147_i166
#ISCELL
  mstr_standard offpage *
  page147_i17
#ISCELL
  mstr_standard offpage *
  page147_i171
#ISCELL
  mstr_standard offpage *
  page147_i172
#CELL
  mstr_discrete res *
  page147_i173
#ISCELL
  mstr_standard offpage *
  page147_i174
#ISCELL
  mstr_standard offpage *
  page147_i175
#ISCELL
  mstr_standard offpage *
  page147_i176
#ISCELL
  mstr_standard offpage *
  page147_i177
#ISCELL
  mstr_standard offpage *
  page147_i178
#ISCELL
  mstr_standard offpage *
  page147_i179
#ISCELL
  mstr_standard offpage *
  page147_i18
#ISCELL
  mstr_standard offpage *
  page147_i19
#ISCELL
  mstr_standard offpage *
  page147_i2
#ISCELL
  w_power w_vcc_circle *
  page147_i20
#CELL
  mstr_discrete res *
  page147_i21
#CELL
  mstr_discrete res *
  page147_i22
#CELL
  mstr_discrete res *
  page147_i23
#CELL
  mstr_discrete res *
  page147_i24
#CELL
  mstr_discrete res *
  page147_i25
#ISCELL
  mstr_standard offpage *
  page147_i34
#ISCELL
  mstr_standard offpage *
  page147_i35
#ISCELL
  mstr_symbols gnd *
  page147_i37
#ISCELL
  mstr_symbols gnd *
  page147_i41
#CELL
  mstr_discrete res *
  page147_i42
#CELL
  mstr_discrete res *
  page147_i43
#ISCELL
  mstr_symbols p3v3_stby *
  page147_i44
#ISCELL
  mstr_standard offpage *
  page147_i47
#ISCELL
  mstr_standard offpage *
  page147_i48
#ISCELL
  mstr_standard offpage *
  page147_i49
#ISCELL
  mstr_standard offpage *
  page147_i50
#ISCELL
  mstr_standard offpage *
  page147_i51
#ISCELL
  mstr_standard offpage *
  page147_i54
#ISCELL
  mstr_standard offpage *
  page147_i55
#ISCELL
  mstr_standard offpage *
  page147_i56
#ISCELL
  mstr_standard offpage *
  page147_i57
#ISCELL
  mstr_standard offpage *
  page147_i58
#ISCELL
  mstr_standard offpage *
  page147_i59
#ISCELL
  mstr_standard offpage *
  page147_i6
#ISCELL
  mstr_standard offpage *
  page147_i60
#CELL
  mstr_discrete res *
  page147_i61
#CELL
  mstr_discrete res *
  page147_i62
#ISCELL
  mstr_symbols gnd *
  page147_i63
#ISCELL
  mstr_symbols gnd *
  page147_i64
#CELL
  mstr_discrete res *
  page147_i65
#CELL
  mstr_discrete res *
  page147_i66
#ISCELL
  mstr_symbols gnd *
  page147_i67
#ISCELL
  mstr_symbols gnd *
  page147_i68
#ISCELL
  mstr_standard offpage *
  page147_i7
#CELL
  mstr_discrete res *
  page147_i75
#ISCELL
  mstr_symbols gnd *
  page147_i76
#ISCELL
  mstr_standard offpage *
  page147_i79
#CELL
  mstr_discrete res *
  page147_i8
#ISCELL
  mstr_standard offpage *
  page147_i81
#ISCELL
  mstr_standard offpage *
  page147_i88
#ISCELL
  mstr_standard offpage *
  page147_i89
#ISCELL
  mstr_standard offpage *
  page147_i9
